# Bryce Canyon_Rear_Drive_Plane_Board_Stackup.xlsx — Stack up_16317-1 (pcb-stackup)
|  |  |  |  |  |  | Version |  |  |  |  |  |  |  |  |  |  |  |  |  |  |  |  |  |  |  |
| Board Number: |  | 16317-1 |  |  |  | 02 |  |  |  |  |  |  |  |  |  |  |  |  |  |  |  |  |  |  |  |
| Project name: |  | Bryce Canyon |  |  |  |  |  |  |  |  |  |  |  |  |  |  |  |  |  |  |  |  |  |  |  |
| Model Name: |  | Rear Drive Plane Board |  |  |  |  |  |  |  |  |  |  |  |  |  |  |  |  |  |  |  |  |  |  |  |
| Layer Count: |  | 8 Layer |  |  |  |  |  |  |  |  |  |  |  |  |  |  |  |  |  |  |  |  |  |  |  |
| Date: |  | 2017-09-25 00:00:00 |  |  |  |  |  |  |  |  |  |  |  |  |  |  |  |  |  |  |  |  |  |  |  |
| Low Loss Material: |  | TU863+VLP (Tg : 180/Td : 370) |  |  |  |  |  |  | Single Ended Type(mil) |  |  |  |  | Differential Type(mil) |  |  |  |  |  |  |  |  |  |  |  |
| Gold Finger(Y/N): |  | N |  |  |  |  |  | Imp | 50 |  |  |  | Imp | 85 |  |  |  |  |  | 100 |  |  |  |  |  |
| Customer: |  | <name> |  |  |  |  |  | Variation | Inner/Outer+/-5ohm |  |  |  | Variation | Inner/Outer+/-10% |  |  |  |  |  | Inner/Outer+/-10% |  |  |  |  |  |
| EE engineer |  | <name> |  |  |  |  |  | Bus | MISC. |  |  |  | Bus | PCIe / Clock |  |  |  |  |  | SATA |  |  |  |  |  |
| SI Engineer |  | <name> |  |  |  |  |  |  |  |  |  |  |  |  |  |  |  |  |  |  |  |  |  |  |  |
|  |  |  |  |  |  |  |  | Type | SE |  |  |  | Type | DP |  |  |  |  |  | DP |  |  |  |  |  |
| Layer |  |  | Thickness |  | Glass/Copper Style | Er | Df(1G) | Layers | 1,3,6,8 |  |  |  | Layers | 1,3,6,8 |  |  |  |  |  | 1,3,6,8 |  |  |  |  |  |
|  |  | Cu oz | Wiwynn |  |  | Wiwynn |  |  | Wiwynn |  |  |  |  | Wiwynn |  |  |  |  |  | Wiwynn |  |  |  |  |  |
|  | Mask |  | 0.5 |  |  | 3.4 | 0.025 |  | Width | Imp | Width | Imp |  | Width | Space | Imp | Width | Space | Imp | Width | Space | Imp | Width | Space | Imp |
| Top | Signal | 0.5 oz+plating | 2.1 |  |  |  |  | S1 | 6.75(L2) | 50.17 |  |  | S1 | 6.5(L2) | 5 | 84.97 |  |  |  | 5(L2) | 6.5 | 99.87 |  |  |  |
|  | Prepreg |  | 4 |  |  | 3.9 | 0.006 |  |  |  |  |  |  |  |  |  |  |  |  |  |  |  |  |  |  |
| L2 | GND | 1 oz | 1.3 |  |  |  |  | P2 | reference layer |  |  |  | P2 | reference layer |  |  |  |  |  | reference layer |  |  |  |  |  |
|  | Core |  | 5 |  |  | 3.9 | 0.006 |  |  |  |  |  |  |  |  |  |  |  |  |  |  |  |  |  |  |
| L3 | Signal | 1 oz | 1.3 |  |  |  |  | S3 | 5.75(L2/L4) | 49.84 |  |  | S3 | 5.5(L2/L4) | 6 | 85.34 |  |  |  | 4.75(L2/L4) | 8.5 | 100.14 |  |  |  |
|  | Prepreg |  | 15 |  |  | 4.5 | 0.006 |  |  |  |  |  |  |  |  |  |  |  |  |  |  |  |  |  |  |
| L4 | POWER | 2 oz | 2.6 |  |  |  |  | P4 | reference layer |  |  |  | P4 | reference layer |  |  |  |  |  | reference layer |  |  |  |  |  |
|  | Core |  | 29.4 |  |  | 4.5 | 0.006 |  |  |  |  |  |  |  |  |  |  |  |  |  |  |  |  |  |  |
| L5 | POWER | 2 oz | 2.6 |  |  |  |  | P5 | reference layer |  |  |  | P5 | reference layer |  |  |  |  |  | reference layer |  |  |  |  |  |
|  | Prepreg |  | 15 |  |  | 4.5 | 0.006 |  |  |  |  |  |  |  |  |  |  |  |  |  |  |  |  |  |  |
| L6 | Signal | 1 oz | 1.3 | 0 | 0 |  |  | S6 | 5.75(L5/L7) | 49.84 |  |  | S6 | 5.5(L5/L7) | 6 | 85.34 |  |  |  | 4.75(L5/L7) | 8.5 | 100.14 |  |  |  |
|  | Core |  | 5 | 0 | 0 | 3.9 | 0.006 |  |  |  |  |  |  |  |  |  |  |  |  |  |  |  |  |  |  |
| L7 | GND | 1 oz | 1.3 | 0 | 0 |  |  | P7 | reference layer |  |  |  | P7 | reference layer |  |  |  |  |  | reference layer |  |  |  |  |  |
|  | Prepreg |  | 4 | 0 | 0 | 3.9 | 0.006 |  |  |  |  |  |  |  |  |  |  |  |  |  |  |  |  |  |  |
| Bottom | Signal | 0.5 oz+plating | 2.1 | 0 | 0 |  |  | S8 | 6.75(L7) | 50.17 |  |  | S8 | 6.5(L7) | 5 | 84.97 |  |  |  | 5(L7) | 6.5 | 99.87 |  |  |  |
|  | Mask |  | 0.5 | 0 |  | 3.4 | 0.025 |  |  |  |  |  |  |  |  |  |  |  |  |  |  |  |  |  |  |
| Thickness requirement: 2.36 ± 10% mm |  | mil | 93 |  |  |  |  |  |  |  |  |  |  |  |  |  |  |  |  |  |  |  |  |  |  |
|  |  | mm | 2.362204724409449 |  |  |  |  |  |  |  |  |  |  |  |  |  |  |  |  |  |  |  |  |  |  |
| Note: | 1. Unit is mil |  |  |  |  |  |  |  |  |  |  |  |  |  |  |  |  |  |  |  |  |  |  |  |  |
|  | 2. The total thickness includes trace and solder mask. |  |  |  |  |  |  |  |  |  |  |  |  |  |  |  |  |  |  |  |  |  |  |  |  |
|  | 3. Minimum hole copper thickness is 1.0 mil. |  |  |  |  |  |  |  |  |  |  |  |  |  |  |  |  |  |  |  |  |  |  |  |  |
|  | 4. Minimum surface copper thickness 1.5 mil. |  |  |  |  |  |  |  |  |  |  |  |  |  |  |  |  |  |  |  |  |  |  |  |  |
|  | 5. If there is no controlled impedance line described as the stackup in the gerber file, PCB supplier can ignore this kind of impedance control directly, but need to inform Wiwynn in engineering question(EQ). |  |  |  |  |  |  |  |  |  |  |  |  |  |  |  |  |  |  |  |  |  |  |  |  |
|  | 6. PCB test coupon requirement and PCB test note are described in the another sheets. |  |  |  |  |  |  |  |  |  |  |  |  |  |  |  |  |  |  |  |  |  |  |  |  |
|  | 7. If there is no "Delta-L" design in gerber file, PCB supplier should design 85 ohm "Delta-L" angle routing coupon and provide the measurement results in FAI report which meet the following criteria: |  |  |  |  |  |  |  |  |  |  |  |  |  |  |  |  |  |  |  |  |  |  |  |  |
|  | For low-loss material |  |  |  |  |  |  |  |  |  |  |  |  |  |  |  |  |  |  |  |  |  |  |  |  |
|  | (1)   0.55 dB/inch @ 4GHz; 1.05 dB/inch @ 8GHz for microstrip routing |  |  |  |  |  |  |  |  |  |  |  |  |  |  |  |  |  |  |  |  |  |  |  |  |
|  | (2)   0.48 dB/inch @ 4GHz; 0.9 dB/inch @ 8GHz for stripline routing |  |  |  |  |  |  |  |  |  |  |  |  |  |  |  |  |  |  |  |  |  |  |  |  |
